(kicad_pcb
	(version 20260206)
	(generator "pcbnew")
	(generator_version "10.0")
	(general
		(thickness 1.6)
		(legacy_teardrops no)
	)
	(paper "A4")
	(title_block
		(title "Bryce Canyon_IOM_IOC_16318-2_OCP.brd")
		(comment 1 "Bryce Canyon / footprints 1147-1154 of 1605")
	)
	(layers
		(0 "F.Cu" signal "TOP")
		(4 "In1.Cu" signal "L2GND")
		(6 "In2.Cu" signal "L3")
		(8 "In3.Cu" signal "L4VCC")
		(10 "In4.Cu" signal "L5VCC")
		(12 "In5.Cu" signal "L6")
		(14 "In6.Cu" signal "L7GND")
		(2 "B.Cu" signal "BOTTOM")
		(9 "F.Adhes" user "F.Adhesive")
		(11 "B.Adhes" user "B.Adhesive")
		(13 "F.Paste" user "Package Geometry/Pastemask Top")
		(15 "B.Paste" user "Package Geometry/Pastemask Bottom")
		(5 "F.SilkS" user "Ref Des/Silkscreen Top")
		(7 "B.SilkS" user "Ref Des/Silkscreen Bottom")
		(1 "F.Mask" user "Board Geometry/Soldermask Top")
		(3 "B.Mask" user "Board Geometry/Soldermask Bottom")
		(17 "Dwgs.User" user "User.Drawings")
		(19 "Cmts.User" user "User.Comments")
		(21 "Eco1.User" user "User.Eco1")
		(23 "Eco2.User" user "User.Eco2")
		(25 "Edge.Cuts" user "Board Geometry/Outline")
		(27 "Margin" user)
		(31 "F.CrtYd" user "Package Geometry/Place Bound Top")
		(29 "B.CrtYd" user "Package Geometry/Place Bound Bottom")
		(35 "F.Fab" user "Ref Des/Assembly Top")
		(33 "B.Fab" user "Ref Des/Assembly Bottom")
	)
	(footprint ""
		(layer "B.Cu")
		(at 197.2945 -63.9699 90)
		(property "Reference" "C395"
			(at 0 0 90)
			(layer "B.SilkS")
			(hide yes)
			(effects
				(font
					(size 1.27 1.27)
				)
				(justify mirror)
			)
		)
		(property "Value" "SC1U16V2KX-7-GP"
			(at -1.7526 -1.6002 90)
			(unlocked yes)
			(layer "B.Fab")
			(hide yes)
			(effects
				(font
					(size 1.016 1.016)
					(thickness 0.1524)
				)
				(justify mirror)
			)
		)
		(property "Device Type" "C402-TO0D2H24"
			(at -1.7526 -3.1242 90)
			(unlocked yes)
			(layer "B.Fab")
			(hide yes)
			(effects
				(font
					(size 1.016 1.016)
					(thickness 0.1524)
				)
				(justify mirror)
			)
		)
		(duplicate_pad_numbers_are_jumpers no)
		(fp_rect
			(start 0.4826 0.889)
			(end -0.4826 -0.889)
			(stroke
				(width 0)
				(type default)
			)
			(fill no)
			(layer "B.CrtYd")
		)
		(fp_rect
			(start 0.4826 0.889)
			(end -0.4826 -0.889)
			(stroke
				(width 0)
				(type default)
			)
			(fill no)
			(layer "B.Fab")
		)
		(pad "1" smd custom
			(at 0 -0.4572 270)
			(size 0.1524 0.1524)
			(layers "B.Cu" "B.Mask" "B.Paste")
			(net "P0V975")
			(options
				(clearance outline)
				(anchor circle)
			)
			(primitives
				(gr_poly
					(pts
						(arc
							(start -0.254 -0.3048)
							(mid -0.325842 -0.275042)
							(end -0.3556 -0.2032)
						)
						(arc
							(start -0.3556 0.2032)
							(mid -0.325842 0.275042)
							(end -0.254 0.3048)
						)
						(arc
							(start 0.254 0.3048)
							(mid 0.325842 0.275042)
							(end 0.3556 0.2032)
						)
						(arc
							(start 0.3556 -0.2032)
							(mid 0.325842 -0.275042)
							(end 0.254 -0.3048)
						)
					)
					(width 0)
					(fill yes)
				)
			)
		)
		(pad "2" smd custom
			(at 0 0.4572 270)
			(size 0.1524 0.1524)
			(layers "B.Cu" "B.Mask" "B.Paste")
			(net "GND")
			(options
				(clearance outline)
				(anchor circle)
			)
			(primitives
				(gr_poly
					(pts
						(arc
							(start -0.254 -0.3048)
							(mid -0.325842 -0.275042)
							(end -0.3556 -0.2032)
						)
						(arc
							(start -0.3556 0.2032)
							(mid -0.325842 0.275042)
							(end -0.254 0.3048)
						)
						(arc
							(start 0.254 0.3048)
							(mid 0.325842 0.275042)
							(end 0.3556 0.2032)
						)
						(arc
							(start 0.3556 -0.2032)
							(mid 0.325842 -0.275042)
							(end 0.254 -0.3048)
						)
					)
					(width 0)
					(fill yes)
				)
			)
		)
	)
	(footprint ""
		(layer "B.Cu")
		(at 40.69842 -129.57556 -90)
		(property "Reference" "R350"
			(at 0 0 90)
			(layer "B.SilkS")
			(hide yes)
			(effects
				(font
					(size 1.27 1.27)
				)
				(justify mirror)
			)
		)
		(property "Value" "0R2J-2-GP"
			(at -0.064008 -3.993896 270)
			(unlocked yes)
			(layer "B.Fab")
			(hide yes)
			(effects
				(font
					(size 1.016 1.016)
					(thickness 0.1524)
				)
				(justify mirror)
			)
		)
		(property "Device Type" "R402H16"
			(at -0.064008 -5.517896 270)
			(unlocked yes)
			(layer "B.Fab")
			(hide yes)
			(effects
				(font
					(size 1.016 1.016)
					(thickness 0.1524)
				)
				(justify mirror)
			)
		)
		(duplicate_pad_numbers_are_jumpers no)
		(fp_line
			(start -0.508 -0.9398)
			(end 0.508 -0.9398)
			(stroke
				(width 0.1524)
				(type default)
			)
			(layer "B.SilkS")
		)
		(fp_line
			(start 0.508 -0.9398)
			(end 0.508 0.9398)
			(stroke
				(width 0.1524)
				(type default)
			)
			(layer "B.SilkS")
		)
		(fp_rect
			(start 0.508 0.9398)
			(end -0.508 -0.9398)
			(stroke
				(width 0)
				(type default)
			)
			(fill no)
			(layer "B.CrtYd")
		)
		(fp_rect
			(start 0.508 0.9398)
			(end -0.508 -0.9398)
			(stroke
				(width 0)
				(type default)
			)
			(fill no)
			(layer "B.Fab")
		)
		(pad "1" smd custom
			(at 0 -0.4445 90)
			(size 0.1397 0.1397)
			(layers "B.Cu" "B.Mask" "B.Paste")
			(net "FM_TPM_PRSNT_N")
			(options
				(clearance outline)
				(anchor circle)
			)
			(primitives
				(gr_poly
					(pts
						(arc
							(start -0.1778 0.2794)
							(mid -0.249642 0.249642)
							(end -0.2794 0.1778)
						)
						(arc
							(start -0.2794 -0.1778)
							(mid -0.249642 -0.249642)
							(end -0.1778 -0.2794)
						)
						(arc
							(start 0.1778 -0.2794)
							(mid 0.249642 -0.249642)
							(end 0.2794 -0.1778)
						)
						(arc
							(start 0.2794 0.1778)
							(mid 0.249642 0.249642)
							(end 0.1778 0.2794)
						)
					)
					(width 0)
					(fill yes)
				)
			)
		)
		(pad "2" smd custom
			(at 0 0.4445 90)
			(size 0.1397 0.1397)
			(layers "B.Cu" "B.Mask" "B.Paste")
			(net "TPM_PRSNT_N_R")
			(options
				(clearance outline)
				(anchor circle)
			)
			(primitives
				(gr_poly
					(pts
						(arc
							(start -0.1778 0.2794)
							(mid -0.249642 0.249642)
							(end -0.2794 0.1778)
						)
						(arc
							(start -0.2794 -0.1778)
							(mid -0.249642 -0.249642)
							(end -0.1778 -0.2794)
						)
						(arc
							(start 0.1778 -0.2794)
							(mid 0.249642 -0.249642)
							(end 0.2794 -0.1778)
						)
						(arc
							(start 0.2794 0.1778)
							(mid 0.249642 0.249642)
							(end 0.1778 0.2794)
						)
					)
					(width 0)
					(fill yes)
				)
			)
		)
	)
	(footprint ""
		(layer "B.Cu")
		(at 54.3814 -132.6642)
		(property "Reference" "C114"
			(at 0 0 0)
			(layer "B.SilkS")
			(hide yes)
			(effects
				(font
					(size 1.27 1.27)
				)
				(justify mirror)
			)
		)
		(property "Value" "SC1U16V3KX-5GP"
			(at 0 -2.8194 0)
			(unlocked yes)
			(layer "B.Fab")
			(hide yes)
			(effects
				(font
					(size 1.016 1.016)
					(thickness 0.1524)
				)
				(justify mirror)
			)
		)
		(property "Device Type" "C603H36"
			(at 0 -4.3434 0)
			(unlocked yes)
			(layer "B.Fab")
			(hide yes)
			(effects
				(font
					(size 1.016 1.016)
					(thickness 0.1524)
				)
				(justify mirror)
			)
		)
		(duplicate_pad_numbers_are_jumpers no)
		(fp_line
			(start -0.508 0)
			(end 0.508 0)
			(stroke
				(width 0.2032)
				(type default)
			)
			(layer "B.SilkS")
		)
		(fp_rect
			(start 0.5842 1.3335)
			(end -0.5842 -1.3335)
			(stroke
				(width 0)
				(type default)
			)
			(fill no)
			(layer "B.CrtYd")
		)
		(fp_rect
			(start 0.5842 1.3335)
			(end -0.5842 -1.3335)
			(stroke
				(width 0)
				(type default)
			)
			(fill no)
			(layer "B.Fab")
		)
		(pad "1" smd custom
			(at 0 -0.762 180)
			(size 0.2159 0.2159)
			(layers "B.Cu" "B.Mask" "B.Paste")
			(net "P1V15_STBY")
			(options
				(clearance outline)
				(anchor circle)
			)
			(primitives
				(gr_poly
					(pts
						(arc
							(start -0.3302 0.4318)
							(mid -0.402042 0.402042)
							(end -0.4318 0.3302)
						)
						(arc
							(start -0.4318 -0.3302)
							(mid -0.402042 -0.402042)
							(end -0.3302 -0.4318)
						)
						(arc
							(start 0.3302 -0.4318)
							(mid 0.402042 -0.402042)
							(end 0.4318 -0.3302)
						)
						(arc
							(start 0.4318 0.3302)
							(mid 0.402042 0.402042)
							(end 0.3302 0.4318)
						)
					)
					(width 0)
					(fill yes)
				)
			)
		)
		(pad "2" smd custom
			(at 0 0.762 180)
			(size 0.2159 0.2159)
			(layers "B.Cu" "B.Mask" "B.Paste")
			(net "GND")
			(options
				(clearance outline)
				(anchor circle)
			)
			(primitives
				(gr_poly
					(pts
						(arc
							(start -0.3302 0.4318)
							(mid -0.402042 0.402042)
							(end -0.4318 0.3302)
						)
						(arc
							(start -0.4318 -0.3302)
							(mid -0.402042 -0.402042)
							(end -0.3302 -0.4318)
						)
						(arc
							(start 0.3302 -0.4318)
							(mid 0.402042 -0.402042)
							(end 0.4318 -0.3302)
						)
						(arc
							(start 0.4318 0.3302)
							(mid 0.402042 0.402042)
							(end 0.3302 0.4318)
						)
					)
					(width 0)
					(fill yes)
				)
			)
		)
	)
	(footprint ""
		(layer "B.Cu")
		(at 55.6768 -135.8392 180)
		(property "Reference" "R295"
			(at 0 0 0)
			(layer "B.SilkS")
			(hide yes)
			(effects
				(font
					(size 1.27 1.27)
				)
				(justify mirror)
			)
		)
		(property "Value" "0R2J-2-GP"
			(at -0.064008 -3.993896 180)
			(unlocked yes)
			(layer "B.Fab")
			(hide yes)
			(effects
				(font
					(size 1.016 1.016)
					(thickness 0.1524)
				)
				(justify mirror)
			)
		)
		(property "Device Type" "R402H16"
			(at -0.064008 -5.517896 180)
			(unlocked yes)
			(layer "B.Fab")
			(hide yes)
			(effects
				(font
					(size 1.016 1.016)
					(thickness 0.1524)
				)
				(justify mirror)
			)
		)
		(duplicate_pad_numbers_are_jumpers no)
		(fp_line
			(start 0.508 -0.9398)
			(end 0.508 0.9398)
			(stroke
				(width 0.1524)
				(type default)
			)
			(layer "B.SilkS")
		)
		(fp_line
			(start -0.508 -0.9398)
			(end 0.508 -0.9398)
			(stroke
				(width 0.1524)
				(type default)
			)
			(layer "B.SilkS")
		)
		(fp_rect
			(start 0.508 0.9398)
			(end -0.508 -0.9398)
			(stroke
				(width 0)
				(type default)
			)
			(fill no)
			(layer "B.CrtYd")
		)
		(fp_rect
			(start 0.508 0.9398)
			(end -0.508 -0.9398)
			(stroke
				(width 0)
				(type default)
			)
			(fill no)
			(layer "B.Fab")
		)
		(pad "1" smd custom
			(at 0 -0.4445)
			(size 0.1397 0.1397)
			(layers "B.Cu" "B.Mask" "B.Paste")
			(net "SCC_RMT_TYPE_0")
			(options
				(clearance outline)
				(anchor circle)
			)
			(primitives
				(gr_poly
					(pts
						(arc
							(start -0.1778 0.2794)
							(mid -0.249642 0.249642)
							(end -0.2794 0.1778)
						)
						(arc
							(start -0.2794 -0.1778)
							(mid -0.249642 -0.249642)
							(end -0.1778 -0.2794)
						)
						(arc
							(start 0.1778 -0.2794)
							(mid 0.249642 -0.249642)
							(end 0.2794 -0.1778)
						)
						(arc
							(start 0.2794 0.1778)
							(mid 0.249642 0.249642)
							(end 0.1778 0.2794)
						)
					)
					(width 0)
					(fill yes)
				)
			)
		)
		(pad "2" smd custom
			(at 0 0.4445)
			(size 0.1397 0.1397)
			(layers "B.Cu" "B.Mask" "B.Paste")
			(net "SCC_RMT_TYPE_0_R")
			(options
				(clearance outline)
				(anchor circle)
			)
			(primitives
				(gr_poly
					(pts
						(arc
							(start -0.1778 0.2794)
							(mid -0.249642 0.249642)
							(end -0.2794 0.1778)
						)
						(arc
							(start -0.2794 -0.1778)
							(mid -0.249642 -0.249642)
							(end -0.1778 -0.2794)
						)
						(arc
							(start 0.1778 -0.2794)
							(mid 0.249642 -0.249642)
							(end 0.2794 -0.1778)
						)
						(arc
							(start 0.2794 0.1778)
							(mid 0.249642 0.249642)
							(end 0.1778 0.2794)
						)
					)
					(width 0)
					(fill yes)
				)
			)
		)
	)
	(footprint ""
		(layer "B.Cu")
		(at 184.268872 -74.793856 -90)
		(property "Reference" "C470"
			(at 0 0 90)
			(layer "B.SilkS")
			(hide yes)
			(effects
				(font
					(size 1.27 1.27)
				)
				(justify mirror)
			)
		)
		(property "Value" "SCD1U16V2KX-3GP"
			(at -1.1811 -2.7051 270)
			(unlocked yes)
			(layer "B.Fab")
			(hide yes)
			(effects
				(font
					(size 1.016 1.016)
					(thickness 0.1524)
				)
				(justify mirror)
			)
		)
		(property "Device Type" "C402H22"
			(at -1.1811 -4.2291 270)
			(unlocked yes)
			(layer "B.Fab")
			(hide yes)
			(effects
				(font
					(size 1.016 1.016)
					(thickness 0.1524)
				)
				(justify mirror)
			)
		)
		(duplicate_pad_numbers_are_jumpers no)
		(fp_rect
			(start 0.4318 0.9525)
			(end -0.4318 -0.9525)
			(stroke
				(width 0)
				(type default)
			)
			(fill no)
			(layer "B.CrtYd")
		)
		(fp_rect
			(start 0.4318 0.9525)
			(end -0.4318 -0.9525)
			(stroke
				(width 0)
				(type default)
			)
			(fill no)
			(layer "B.Fab")
		)
		(pad "1" smd custom
			(at 0 -0.4445 90)
			(size 0.1524 0.1524)
			(layers "B.Cu" "B.Mask" "B.Paste")
			(net "P1V8")
			(options
				(clearance outline)
				(anchor circle)
			)
			(primitives
				(gr_poly
					(pts
						(arc
							(start 0.3048 0.2032)
							(mid 0.275042 0.275042)
							(end 0.2032 0.3048)
						)
						(arc
							(start -0.2032 0.3048)
							(mid -0.275042 0.275042)
							(end -0.3048 0.2032)
						)
						(arc
							(start -0.3048 -0.2032)
							(mid -0.275042 -0.275042)
							(end -0.2032 -0.3048)
						)
						(arc
							(start 0.2032 -0.3048)
							(mid 0.275042 -0.275042)
							(end 0.3048 -0.2032)
						)
					)
					(width 0)
					(fill yes)
				)
			)
		)
		(pad "2" smd custom
			(at 0 0.4445 90)
			(size 0.1524 0.1524)
			(layers "B.Cu" "B.Mask" "B.Paste")
			(net "GND")
			(options
				(clearance outline)
				(anchor circle)
			)
			(primitives
				(gr_poly
					(pts
						(arc
							(start 0.3048 0.2032)
							(mid 0.275042 0.275042)
							(end 0.2032 0.3048)
						)
						(arc
							(start -0.2032 0.3048)
							(mid -0.275042 0.275042)
							(end -0.3048 0.2032)
						)
						(arc
							(start -0.3048 -0.2032)
							(mid -0.275042 -0.275042)
							(end -0.2032 -0.3048)
						)
						(arc
							(start 0.2032 -0.3048)
							(mid 0.275042 -0.275042)
							(end 0.3048 -0.2032)
						)
					)
					(width 0)
					(fill yes)
				)
			)
		)
	)
	(footprint ""
		(layer "B.Cu")
		(at 193.0146 -124.3584 180)
		(property "Reference" "C286"
			(at 0 0 0)
			(layer "B.SilkS")
			(hide yes)
			(effects
				(font
					(size 1.27 1.27)
				)
				(justify mirror)
			)
		)
		(property "Value" "SCD33U16V3KX-1GP"
			(at 0 -2.8194 180)
			(unlocked yes)
			(layer "B.Fab")
			(hide yes)
			(effects
				(font
					(size 1.016 1.016)
					(thickness 0.1524)
				)
				(justify mirror)
			)
		)
		(property "Device Type" "C603H36"
			(at 0 -4.3434 180)
			(unlocked yes)
			(layer "B.Fab")
			(hide yes)
			(effects
				(font
					(size 1.016 1.016)
					(thickness 0.1524)
				)
				(justify mirror)
			)
		)
		(duplicate_pad_numbers_are_jumpers no)
		(fp_line
			(start -0.508 0)
			(end 0.508 0)
			(stroke
				(width 0.2032)
				(type default)
			)
			(layer "B.SilkS")
		)
		(fp_rect
			(start 0.5842 1.3335)
			(end -0.5842 -1.3335)
			(stroke
				(width 0)
				(type default)
			)
			(fill no)
			(layer "B.CrtYd")
		)
		(fp_rect
			(start 0.5842 1.3335)
			(end -0.5842 -1.3335)
			(stroke
				(width 0)
				(type default)
			)
			(fill no)
			(layer "B.Fab")
		)
		(pad "1" smd custom
			(at 0 -0.762)
			(size 0.2159 0.2159)
			(layers "B.Cu" "B.Mask" "B.Paste")
			(net "AVSO_VREF")
			(options
				(clearance outline)
				(anchor circle)
			)
			(primitives
				(gr_poly
					(pts
						(arc
							(start -0.3302 0.4318)
							(mid -0.402042 0.402042)
							(end -0.4318 0.3302)
						)
						(arc
							(start -0.4318 -0.3302)
							(mid -0.402042 -0.402042)
							(end -0.3302 -0.4318)
						)
						(arc
							(start 0.3302 -0.4318)
							(mid 0.402042 -0.402042)
							(end 0.4318 -0.3302)
						)
						(arc
							(start 0.4318 0.3302)
							(mid 0.402042 0.402042)
							(end 0.3302 0.4318)
						)
					)
					(width 0)
					(fill yes)
				)
			)
		)
		(pad "2" smd custom
			(at 0 0.762)
			(size 0.2159 0.2159)
			(layers "B.Cu" "B.Mask" "B.Paste")
			(net "GND")
			(options
				(clearance outline)
				(anchor circle)
			)
			(primitives
				(gr_poly
					(pts
						(arc
							(start -0.3302 0.4318)
							(mid -0.402042 0.402042)
							(end -0.4318 0.3302)
						)
						(arc
							(start -0.4318 -0.3302)
							(mid -0.402042 -0.402042)
							(end -0.3302 -0.4318)
						)
						(arc
							(start 0.3302 -0.4318)
							(mid 0.402042 -0.402042)
							(end 0.4318 -0.3302)
						)
						(arc
							(start 0.4318 0.3302)
							(mid 0.402042 0.402042)
							(end 0.3302 0.4318)
						)
					)
					(width 0)
					(fill yes)
				)
			)
		)
	)
	(footprint ""
		(layer "B.Cu")
		(at 157.099 -122.174 -90)
		(property "Reference" "C216"
			(at 0 0 90)
			(layer "B.SilkS")
			(hide yes)
			(effects
				(font
					(size 1.27 1.27)
				)
				(justify mirror)
			)
		)
		(property "Value" "SC10U6D3V5KX-4GP"
			(at 0.0762 -6.1214 270)
			(unlocked yes)
			(layer "B.Fab")
			(hide yes)
			(effects
				(font
					(size 1.016 1.016)
					(thickness 0.1524)
				)
				(justify mirror)
			)
		)
		(property "Device Type" "C805H58"
			(at 0.0762 -8.1534 270)
			(unlocked yes)
			(layer "B.Fab")
			(hide yes)
			(effects
				(font
					(size 1.016 1.016)
					(thickness 0.1524)
				)
				(justify mirror)
			)
		)
		(duplicate_pad_numbers_are_jumpers no)
		(fp_line
			(start -0.635 0)
			(end 0.635 0)
			(stroke
				(width 0.508)
				(type default)
			)
			(layer "B.SilkS")
		)
		(fp_rect
			(start 0.9652 1.778)
			(end -0.9652 -1.778)
			(stroke
				(width 0)
				(type default)
			)
			(fill no)
			(layer "B.CrtYd")
		)
		(fp_poly
			(pts
				(xy 0.9652 -1.778) (xy -0.9652 -1.778) (xy -0.9652 1.778) (xy 0.9652 1.778)
			)
			(stroke
				(width 0)
				(type default)
			)
			(fill no)
			(layer "B.Fab")
		)
		(pad "1" smd rect
			(at 0 -0.9652 90)
			(size 1.397 1.143)
			(layers "B.Cu" "B.Mask" "B.Paste")
			(net "P1V8_STBY")
		)
		(pad "2" smd rect
			(at 0 0.9652 90)
			(size 1.397 1.143)
			(layers "B.Cu" "B.Mask" "B.Paste")
			(net "GND")
		)
	)
	(footprint ""
		(layer "B.Cu")
		(at 41.3258 -131.7752 180)
		(property "Reference" "R370"
			(at 0 0 0)
			(layer "B.SilkS")
			(hide yes)
			(effects
				(font
					(size 1.27 1.27)
				)
				(justify mirror)
			)
		)
		(property "Value" "4K7R2F-GP"
			(at -0.064008 -3.993896 180)
			(unlocked yes)
			(layer "B.Fab")
			(hide yes)
			(effects
				(font
					(size 1.016 1.016)
					(thickness 0.1524)
				)
				(justify mirror)
			)
		)
		(property "Device Type" "R402H16"
			(at -0.064008 -5.517896 180)
			(unlocked yes)
			(layer "B.Fab")
			(hide yes)
			(effects
				(font
					(size 1.016 1.016)
					(thickness 0.1524)
				)
				(justify mirror)
			)
		)
		(duplicate_pad_numbers_are_jumpers no)
		(fp_line
			(start 0.508 -0.9398)
			(end 0.508 0.9398)
			(stroke
				(width 0.1524)
				(type default)
			)
			(layer "B.SilkS")
		)
		(fp_line
			(start -0.508 -0.9398)
			(end 0.508 -0.9398)
			(stroke
				(width 0.1524)
				(type default)
			)
			(layer "B.SilkS")
		)
		(fp_rect
			(start 0.508 0.9398)
			(end -0.508 -0.9398)
			(stroke
				(width 0)
				(type default)
			)
			(fill no)
			(layer "B.CrtYd")
		)
		(fp_rect
			(start 0.508 0.9398)
			(end -0.508 -0.9398)
			(stroke
				(width 0)
				(type default)
			)
			(fill no)
			(layer "B.Fab")
		)
		(pad "1" smd custom
			(at 0 -0.4445)
			(size 0.1397 0.1397)
			(layers "B.Cu" "B.Mask" "B.Paste")
			(net "P3V3_STBY")
			(options
				(clearance outline)
				(anchor circle)
			)
			(primitives
				(gr_poly
					(pts
						(arc
							(start -0.1778 0.2794)
							(mid -0.249642 0.249642)
							(end -0.2794 0.1778)
						)
						(arc
							(start -0.2794 -0.1778)
							(mid -0.249642 -0.249642)
							(end -0.1778 -0.2794)
						)
						(arc
							(start 0.1778 -0.2794)
							(mid 0.249642 -0.249642)
							(end 0.2794 -0.1778)
						)
						(arc
							(start 0.2794 0.1778)
							(mid 0.249642 0.249642)
							(end 0.1778 0.2794)
						)
					)
					(width 0)
					(fill yes)
				)
			)
		)
		(pad "2" smd custom
			(at 0 0.4445)
			(size 0.1397 0.1397)
			(layers "B.Cu" "B.Mask" "B.Paste")
			(net "BMC_SPI_MOSI")
			(options
				(clearance outline)
				(anchor circle)
			)
			(primitives
				(gr_poly
					(pts
						(arc
							(start -0.1778 0.2794)
							(mid -0.249642 0.249642)
							(end -0.2794 0.1778)
						)
						(arc
							(start -0.2794 -0.1778)
							(mid -0.249642 -0.249642)
							(end -0.1778 -0.2794)
						)
						(arc
							(start 0.1778 -0.2794)
							(mid 0.249642 -0.249642)
							(end 0.2794 -0.1778)
						)
						(arc
							(start 0.2794 0.1778)
							(mid 0.249642 0.249642)
							(end 0.1778 0.2794)
						)
					)
					(width 0)
					(fill yes)
				)
			)
		)
	)
)
